(kicad_pcb
	(version 20260206)
	(generator "pcbnew")
	(generator_version "10.0")
	(general
		(thickness 1.6)
		(legacy_teardrops no)
	)
	(paper "A4")
	(title_block
		(title "timecard-production-celestica-r4006 — R4006-B0001-02_R01.brd")
		(comment 1 "Time Appliance Project (Time Card) / footprints 748-752 of 1113")
	)
	(layers
		(0 "F.Cu" signal "TOP")
		(4 "In1.Cu" signal "L02_GND1")
		(6 "In2.Cu" signal "L03_SIG1")
		(8 "In3.Cu" signal "L04_GND2")
		(10 "In4.Cu" signal "L05_VCC1")
		(12 "In5.Cu" signal "L06_VCC2")
		(14 "In6.Cu" signal "L07_GND3")
		(16 "In7.Cu" signal "L08_SIG2")
		(18 "In8.Cu" signal "L09_GND4")
		(2 "B.Cu" signal "BOTTOM")
		(9 "F.Adhes" user "F.Adhesive")
		(11 "B.Adhes" user "B.Adhesive")
		(13 "F.Paste" user "Package Geometry/Pastemask Top")
		(15 "B.Paste" user "Package Geometry/Pastemask Bottom")
		(5 "F.SilkS" user "Ref Des/Silkscreen Top")
		(7 "B.SilkS" user "Ref Des/Silkscreen Bottom")
		(1 "F.Mask" user "Board Geometry/Soldermask Top")
		(3 "B.Mask" user "Board Geometry/Soldermask Bottom")
		(17 "Dwgs.User" user "User.Drawings")
		(19 "Cmts.User" user "User.Comments")
		(21 "Eco1.User" user "User.Eco1")
		(23 "Eco2.User" user "User.Eco2")
		(25 "Edge.Cuts" user "Board Geometry/Outline")
		(27 "Margin" user)
		(31 "F.CrtYd" user "Package Geometry/Place Bound Top")
		(29 "B.CrtYd" user "Package Geometry/Place Bound Bottom")
		(35 "F.Fab" user "Ref Des/Assembly Top")
		(33 "B.Fab" user "Ref Des/Assembly Bottom")
	)
	(footprint ""
		(layer "B.Cu")
		(at 64.516 -55.753 90)
		(property "Reference" "R99"
			(at -6.35 0.34163 270)
			(unlocked yes)
			(layer "B.SilkS")
			(effects
				(font
					(size 0.7874 0.5842)
					(thickness 0.1524)
				)
				(justify mirror)
			)
		)
		(property "Value" "VAL*"
			(at -0.02032 2.13233 90)
			(unlocked yes)
			(layer "B.Fab")
			(hide yes)
			(effects
				(font
					(size 0.7874 0.5842)
					(thickness 0.1524)
				)
				(justify mirror)
			)
		)
		(property "Tolerance" "TOL*"
			(at -0.044704 3.05435 90)
			(unlocked yes)
			(layer "Cmts.User")
			(hide yes)
			(effects
				(font
					(size 0.7874 0.5842)
					(thickness 0.1524)
				)
				(justify mirror)
			)
		)
		(property "User Part Number" "PARTNUM*"
			(at -0.02032 4.024884 90)
			(unlocked yes)
			(layer "Cmts.User")
			(hide yes)
			(effects
				(font
					(size 0.7874 0.5842)
					(thickness 0.1524)
				)
				(justify mirror)
			)
		)
		(property "Device Type" "RESISTOR-G155-14701-01,4.7KOHMA"
			(at -0.008382 1.210564 90)
			(unlocked yes)
			(layer "B.Fab")
			(hide yes)
			(effects
				(font
					(size 0.7874 0.5842)
					(thickness 0.1524)
				)
				(justify mirror)
			)
		)
		(duplicate_pad_numbers_are_jumpers no)
		(fp_line
			(start 1.143 -0.5588)
			(end 1.143 0.5588)
			(stroke
				(width 0.1)
				(type default)
			)
			(layer "B.SilkS")
		)
		(fp_line
			(start -1.143 -0.5588)
			(end 1.143 -0.5588)
			(stroke
				(width 0.1)
				(type default)
			)
			(layer "B.SilkS")
		)
		(fp_line
			(start 1.143 0.5588)
			(end -1.143 0.5588)
			(stroke
				(width 0.1)
				(type default)
			)
			(layer "B.SilkS")
		)
		(fp_line
			(start -1.143 0.5588)
			(end -1.143 -0.5588)
			(stroke
				(width 0.1)
				(type default)
			)
			(layer "B.SilkS")
		)
		(fp_rect
			(start -1.143 -0.5588)
			(end 1.143 0.5588)
			(stroke
				(width 0)
				(type default)
			)
			(fill no)
			(layer "B.CrtYd")
		)
		(fp_line
			(start 0.508 -0.3048)
			(end 0.508 0.3048)
			(stroke
				(width 0.1)
				(type default)
			)
			(layer "B.Fab")
		)
		(fp_line
			(start -0.508 -0.3048)
			(end 0.508 -0.3048)
			(stroke
				(width 0.1)
				(type default)
			)
			(layer "B.Fab")
		)
		(fp_line
			(start 0.508 0.3048)
			(end -0.508 0.3048)
			(stroke
				(width 0.1)
				(type default)
			)
			(layer "B.Fab")
		)
		(fp_line
			(start -0.508 0.3048)
			(end -0.508 -0.3048)
			(stroke
				(width 0.1)
				(type default)
			)
			(layer "B.Fab")
		)
		(pad "1" smd rect
			(at 0.5334 0 270)
			(size 0.7112 0.6096)
			(layers "B.Cu" "B.Mask" "B.Paste")
			(net "FPGA_OUT_MACUSBPOWER_EN")
		)
		(pad "2" smd rect
			(at -0.5334 0 270)
			(size 0.7112 0.6096)
			(layers "B.Cu" "B.Mask" "B.Paste")
			(net "SG")
		)
		(zone
			(layer "B.Cu")
			(hatch none 0.5)
			(connect_pads
				(clearance 0)
			)
			(min_thickness 0.25)
			(keepout
				(tracks allowed)
				(vias not_allowed)
				(pads allowed)
				(copperpour not_allowed)
				(footprints allowed)
			)
			(placement
				(enabled no)
				(sheetname "")
			)
			(fill
				(thermal_gap 0.5)
				(thermal_bridge_width 0.5)
				(island_removal_mode 0)
			)
			(polygon
				(pts
					(xy 64.2112 -55.6768) (xy 64.8208 -55.6768) (xy 64.8208 -55.8292) (xy 64.2112 -55.8292)
				)
			)
		)
	)
	(footprint ""
		(layer "B.Cu")
		(at 65.786 -58.039 90)
		(property "Reference" "C69"
			(at -2.794 -0.03937 270)
			(unlocked yes)
			(layer "B.SilkS")
			(effects
				(font
					(size 0.7874 0.5842)
					(thickness 0.1524)
				)
				(justify mirror)
			)
		)
		(property "Value" "VAL*"
			(at -0.0762 2.067306 90)
			(unlocked yes)
			(layer "B.Fab")
			(hide yes)
			(effects
				(font
					(size 0.7874 0.5842)
					(thickness 0.1524)
				)
				(justify mirror)
			)
		)
		(property "Device Type" "CAPACITOR-G105-0B104-EK,0.1UF,A"
			(at -0.0508 1.127506 90)
			(unlocked yes)
			(layer "B.Fab")
			(hide yes)
			(effects
				(font
					(size 0.7874 0.5842)
					(thickness 0.1524)
				)
				(justify mirror)
			)
		)
		(property "User Part Number" "PARTNUM*"
			(at -0.1016 4.023106 90)
			(unlocked yes)
			(layer "Cmts.User")
			(hide yes)
			(effects
				(font
					(size 0.7874 0.5842)
					(thickness 0.1524)
				)
				(justify mirror)
			)
		)
		(property "Tolerance" "TOL*"
			(at -0.0762 3.032506 90)
			(unlocked yes)
			(layer "Cmts.User")
			(hide yes)
			(effects
				(font
					(size 0.7874 0.5842)
					(thickness 0.1524)
				)
				(justify mirror)
			)
		)
		(duplicate_pad_numbers_are_jumpers no)
		(fp_line
			(start 1.143 -0.5588)
			(end 1.143 0.5588)
			(stroke
				(width 0.1)
				(type default)
			)
			(layer "B.SilkS")
		)
		(fp_line
			(start -1.143 -0.5588)
			(end 1.143 -0.5588)
			(stroke
				(width 0.1)
				(type default)
			)
			(layer "B.SilkS")
		)
		(fp_line
			(start 1.143 0.5588)
			(end -1.143 0.5588)
			(stroke
				(width 0.1)
				(type default)
			)
			(layer "B.SilkS")
		)
		(fp_line
			(start -1.143 0.5588)
			(end -1.143 -0.5588)
			(stroke
				(width 0.1)
				(type default)
			)
			(layer "B.SilkS")
		)
		(fp_rect
			(start -1.143 -0.5588)
			(end 1.143 0.5588)
			(stroke
				(width 0)
				(type default)
			)
			(fill no)
			(layer "B.CrtYd")
		)
		(fp_line
			(start 0.508 -0.3048)
			(end 0.508 0.3048)
			(stroke
				(width 0.1)
				(type default)
			)
			(layer "B.Fab")
		)
		(fp_line
			(start -0.508 -0.3048)
			(end 0.508 -0.3048)
			(stroke
				(width 0.1)
				(type default)
			)
			(layer "B.Fab")
		)
		(fp_line
			(start 0.508 0.3048)
			(end -0.508 0.3048)
			(stroke
				(width 0.1)
				(type default)
			)
			(layer "B.Fab")
		)
		(fp_line
			(start -0.508 0.3048)
			(end -0.508 -0.3048)
			(stroke
				(width 0.1)
				(type default)
			)
			(layer "B.Fab")
		)
		(pad "1" smd rect
			(at 0.5334 0 270)
			(size 0.7112 0.6096)
			(layers "B.Cu" "B.Mask" "B.Paste")
			(net "USB_PWR_EN")
		)
		(pad "2" smd rect
			(at -0.5334 0 270)
			(size 0.7112 0.6096)
			(layers "B.Cu" "B.Mask" "B.Paste")
			(net "SG")
		)
		(zone
			(layer "B.Cu")
			(hatch none 0.5)
			(connect_pads
				(clearance 0)
			)
			(min_thickness 0.25)
			(keepout
				(tracks allowed)
				(vias not_allowed)
				(pads allowed)
				(copperpour not_allowed)
				(footprints allowed)
			)
			(placement
				(enabled no)
				(sheetname "")
			)
			(fill
				(thermal_gap 0.5)
				(thermal_bridge_width 0.5)
				(island_removal_mode 0)
			)
			(polygon
				(pts
					(xy 65.4812 -57.9628) (xy 66.0908 -57.9628) (xy 66.0908 -58.1152) (xy 65.4812 -58.1152)
				)
			)
		)
	)
	(footprint ""
		(layer "B.Cu")
		(at 71.5645 -49.403 180)
		(property "Reference" "R89"
			(at 2.3495 -0.03937 0)
			(unlocked yes)
			(layer "B.SilkS")
			(effects
				(font
					(size 0.7874 0.5842)
					(thickness 0.1524)
				)
				(justify mirror)
			)
		)
		(property "Value" "VAL*"
			(at -0.02032 2.13233 180)
			(unlocked yes)
			(layer "B.Fab")
			(hide yes)
			(effects
				(font
					(size 0.7874 0.5842)
					(thickness 0.1524)
				)
				(justify mirror)
			)
		)
		(property "Tolerance" "TOL*"
			(at -0.044704 3.05435 180)
			(unlocked yes)
			(layer "Cmts.User")
			(hide yes)
			(effects
				(font
					(size 0.7874 0.5842)
					(thickness 0.1524)
				)
				(justify mirror)
			)
		)
		(property "User Part Number" "PARTNUM*"
			(at -0.02032 4.024884 180)
			(unlocked yes)
			(layer "Cmts.User")
			(hide yes)
			(effects
				(font
					(size 0.7874 0.5842)
					(thickness 0.1524)
				)
				(justify mirror)
			)
		)
		(property "Device Type" "RESISTOR-G155-11000-01,100OHM,A"
			(at -0.008382 1.210564 180)
			(unlocked yes)
			(layer "B.Fab")
			(hide yes)
			(effects
				(font
					(size 0.7874 0.5842)
					(thickness 0.1524)
				)
				(justify mirror)
			)
		)
		(duplicate_pad_numbers_are_jumpers no)
		(fp_line
			(start 1.143 0.5588)
			(end -1.143 0.5588)
			(stroke
				(width 0.1)
				(type default)
			)
			(layer "B.SilkS")
		)
		(fp_line
			(start 1.143 -0.5588)
			(end 1.143 0.5588)
			(stroke
				(width 0.1)
				(type default)
			)
			(layer "B.SilkS")
		)
		(fp_line
			(start -1.143 0.5588)
			(end -1.143 -0.5588)
			(stroke
				(width 0.1)
				(type default)
			)
			(layer "B.SilkS")
		)
		(fp_line
			(start -1.143 -0.5588)
			(end 1.143 -0.5588)
			(stroke
				(width 0.1)
				(type default)
			)
			(layer "B.SilkS")
		)
		(fp_rect
			(start -1.143 0.5588)
			(end 1.143 -0.5588)
			(stroke
				(width 0)
				(type default)
			)
			(fill no)
			(layer "B.CrtYd")
		)
		(fp_line
			(start 0.508 0.3048)
			(end -0.508 0.3048)
			(stroke
				(width 0.1)
				(type default)
			)
			(layer "B.Fab")
		)
		(fp_line
			(start 0.508 -0.3048)
			(end 0.508 0.3048)
			(stroke
				(width 0.1)
				(type default)
			)
			(layer "B.Fab")
		)
		(fp_line
			(start -0.508 0.3048)
			(end -0.508 -0.3048)
			(stroke
				(width 0.1)
				(type default)
			)
			(layer "B.Fab")
		)
		(fp_line
			(start -0.508 -0.3048)
			(end 0.508 -0.3048)
			(stroke
				(width 0.1)
				(type default)
			)
			(layer "B.Fab")
		)
		(pad "1" smd rect
			(at 0.5334 0)
			(size 0.7112 0.6096)
			(layers "B.Cu" "B.Mask" "B.Paste")
			(net "R_MAC_PPS_IN1P")
		)
		(pad "2" smd rect
			(at -0.5334 0)
			(size 0.7112 0.6096)
			(layers "B.Cu" "B.Mask" "B.Paste")
			(net "R_MAC_PPS_IN1N")
		)
		(zone
			(layer "B.Cu")
			(hatch none 0.5)
			(connect_pads
				(clearance 0)
			)
			(min_thickness 0.25)
			(keepout
				(tracks allowed)
				(vias not_allowed)
				(pads allowed)
				(copperpour not_allowed)
				(footprints allowed)
			)
			(placement
				(enabled no)
				(sheetname "")
			)
			(fill
				(thermal_gap 0.5)
				(thermal_bridge_width 0.5)
				(island_removal_mode 0)
			)
			(polygon
				(pts
					(xy 71.6407 -49.7078) (xy 71.4883 -49.7078) (xy 71.4883 -49.0982) (xy 71.6407 -49.0982)
				)
			)
		)
	)
	(footprint ""
		(layer "B.Cu")
		(at 13.589 -22.987 90)
		(property "Reference" "R493"
			(at 0 0.98425 270)
			(unlocked yes)
			(layer "B.SilkS")
			(effects
				(font
					(size 0.635 0.4064)
					(thickness 0.1524)
				)
				(justify mirror)
			)
		)
		(property "Value" "VAL*"
			(at -0.02032 2.13233 90)
			(unlocked yes)
			(layer "B.Fab")
			(hide yes)
			(effects
				(font
					(size 0.7874 0.5842)
					(thickness 0.1524)
				)
				(justify mirror)
			)
		)
		(property "Tolerance" "TOL*"
			(at -0.044704 3.05435 90)
			(unlocked yes)
			(layer "Cmts.User")
			(hide yes)
			(effects
				(font
					(size 0.7874 0.5842)
					(thickness 0.1524)
				)
				(justify mirror)
			)
		)
		(property "User Part Number" "PARTNUM*"
			(at -0.02032 4.024884 90)
			(unlocked yes)
			(layer "Cmts.User")
			(hide yes)
			(effects
				(font
					(size 0.7874 0.5842)
					(thickness 0.1524)
				)
				(justify mirror)
			)
		)
		(property "Device Type" "RESISTOR-G155-100R0-J0,0OHM,-"
			(at -0.008382 1.210564 90)
			(unlocked yes)
			(layer "B.Fab")
			(hide yes)
			(effects
				(font
					(size 0.7874 0.5842)
					(thickness 0.1524)
				)
				(justify mirror)
			)
		)
		(duplicate_pad_numbers_are_jumpers no)
		(fp_line
			(start 1.143 -0.5588)
			(end 1.143 0.5588)
			(stroke
				(width 0.1)
				(type default)
			)
			(layer "B.SilkS")
		)
		(fp_line
			(start -1.143 -0.5588)
			(end 1.143 -0.5588)
			(stroke
				(width 0.1)
				(type default)
			)
			(layer "B.SilkS")
		)
		(fp_line
			(start 1.143 0.5588)
			(end -1.143 0.5588)
			(stroke
				(width 0.1)
				(type default)
			)
			(layer "B.SilkS")
		)
		(fp_line
			(start -1.143 0.5588)
			(end -1.143 -0.5588)
			(stroke
				(width 0.1)
				(type default)
			)
			(layer "B.SilkS")
		)
		(fp_poly
			(pts
				(xy 1.143 0.5588) (xy -1.143 0.5588) (xy -1.143 -0.5588) (xy 1.143 -0.5588)
			)
			(stroke
				(width 0)
				(type default)
			)
			(fill no)
			(layer "B.CrtYd")
		)
		(fp_line
			(start 0.508 -0.3048)
			(end 0.508 0.3048)
			(stroke
				(width 0.1)
				(type default)
			)
			(layer "B.Fab")
		)
		(fp_line
			(start -0.508 -0.3048)
			(end 0.508 -0.3048)
			(stroke
				(width 0.1)
				(type default)
			)
			(layer "B.Fab")
		)
		(fp_line
			(start 0.508 0.3048)
			(end -0.508 0.3048)
			(stroke
				(width 0.1)
				(type default)
			)
			(layer "B.Fab")
		)
		(fp_line
			(start -0.508 0.3048)
			(end -0.508 -0.3048)
			(stroke
				(width 0.1)
				(type default)
			)
			(layer "B.Fab")
		)
		(pad "1" smd rect
			(at 0.5334 0 270)
			(size 0.7112 0.6096)
			(layers "B.Cu" "B.Mask" "B.Paste")
			(net "UNNAMED_12_CAPACITOR_I321_2")
		)
		(pad "2" smd rect
			(at -0.5334 0 270)
			(size 0.7112 0.6096)
			(layers "B.Cu" "B.Mask" "B.Paste")
			(net "UNNAMED_12_74HCT2G125DPTSSOP8_3")
		)
		(zone
			(layer "B.Cu")
			(hatch none 0.5)
			(connect_pads
				(clearance 0)
			)
			(min_thickness 0.25)
			(keepout
				(tracks allowed)
				(vias not_allowed)
				(pads allowed)
				(copperpour not_allowed)
				(footprints allowed)
			)
			(placement
				(enabled no)
				(sheetname "")
			)
			(fill
				(thermal_gap 0.5)
				(thermal_bridge_width 0.5)
				(island_removal_mode 0)
			)
			(polygon
				(pts
					(xy 13.8938 -23.0632) (xy 13.2842 -23.0632) (xy 13.2842 -22.9108) (xy 13.8938 -22.9108)
				)
			)
		)
		(zone
			(layer "B.Cu")
			(hatch none 0.5)
			(connect_pads
				(clearance 0)
			)
			(min_thickness 0.25)
			(keepout
				(tracks not_allowed)
				(vias allowed)
				(pads allowed)
				(copperpour not_allowed)
				(footprints allowed)
			)
			(placement
				(enabled no)
				(sheetname "")
			)
			(fill
				(thermal_gap 0.5)
				(thermal_bridge_width 0.5)
				(island_removal_mode 0)
			)
			(polygon
				(pts
					(xy 13.8938 -23.0632) (xy 13.2842 -23.0632) (xy 13.2842 -22.9108) (xy 13.8938 -22.9108)
				)
			)
		)
	)
	(footprint ""
		(layer "B.Cu")
		(at 30.988 -91.059 -90)
		(property "Reference" "C99"
			(at -2.794 -0.21463 270)
			(unlocked yes)
			(layer "B.SilkS")
			(effects
				(font
					(size 0.7874 0.5842)
					(thickness 0.1524)
				)
				(justify mirror)
			)
		)
		(property "Value" "VAL*"
			(at -0.02032 2.13233 270)
			(unlocked yes)
			(layer "B.Fab")
			(hide yes)
			(effects
				(font
					(size 0.7874 0.5842)
					(thickness 0.1524)
				)
				(justify mirror)
			)
		)
		(property "Tolerance" "TOL*"
			(at -0.044704 3.05435 270)
			(unlocked yes)
			(layer "Cmts.User")
			(hide yes)
			(effects
				(font
					(size 0.7874 0.5842)
					(thickness 0.1524)
				)
				(justify mirror)
			)
		)
		(property "User Part Number" "PARTNUM*"
			(at -0.02032 4.024884 270)
			(unlocked yes)
			(layer "Cmts.User")
			(hide yes)
			(effects
				(font
					(size 0.7874 0.5842)
					(thickness 0.1524)
				)
				(justify mirror)
			)
		)
		(property "Device Type" "CAPACITOR-G105-0F475-BM,4.7UF,A"
			(at -0.008382 1.210564 270)
			(unlocked yes)
			(layer "B.Fab")
			(hide yes)
			(effects
				(font
					(size 0.7874 0.5842)
					(thickness 0.1524)
				)
				(justify mirror)
			)
		)
		(duplicate_pad_numbers_are_jumpers no)
		(fp_line
			(start -1.143 0.5588)
			(end -1.143 -0.5588)
			(stroke
				(width 0.1)
				(type default)
			)
			(layer "B.SilkS")
		)
		(fp_line
			(start 1.143 0.5588)
			(end -1.143 0.5588)
			(stroke
				(width 0.1)
				(type default)
			)
			(layer "B.SilkS")
		)
		(fp_line
			(start -1.143 -0.5588)
			(end 1.143 -0.5588)
			(stroke
				(width 0.1)
				(type default)
			)
			(layer "B.SilkS")
		)
		(fp_line
			(start 1.143 -0.5588)
			(end 1.143 0.5588)
			(stroke
				(width 0.1)
				(type default)
			)
			(layer "B.SilkS")
		)
		(fp_poly
			(pts
				(xy 1.143 0.5588) (xy -1.143 0.5588) (xy -1.143 -0.5588) (xy 1.143 -0.5588)
			)
			(stroke
				(width 0)
				(type default)
			)
			(fill no)
			(layer "B.CrtYd")
		)
		(fp_line
			(start -0.508 0.3048)
			(end -0.508 -0.3048)
			(stroke
				(width 0.1)
				(type default)
			)
			(layer "B.Fab")
		)
		(fp_line
			(start 0.508 0.3048)
			(end -0.508 0.3048)
			(stroke
				(width 0.1)
				(type default)
			)
			(layer "B.Fab")
		)
		(fp_line
			(start -0.508 -0.3048)
			(end 0.508 -0.3048)
			(stroke
				(width 0.1)
				(type default)
			)
			(layer "B.Fab")
		)
		(fp_line
			(start 0.508 -0.3048)
			(end 0.508 0.3048)
			(stroke
				(width 0.1)
				(type default)
			)
			(layer "B.Fab")
		)
		(pad "1" smd rect
			(at 0.5334 0 90)
			(size 0.7112 0.6096)
			(layers "B.Cu" "B.Mask" "B.Paste")
			(net "XP3R3V_VPHY")
		)
		(pad "2" smd rect
			(at -0.5334 0 90)
			(size 0.7112 0.6096)
			(layers "B.Cu" "B.Mask" "B.Paste")
			(net "SG")
		)
		(zone
			(layer "B.Cu")
			(hatch none 0.5)
			(connect_pads
				(clearance 0)
			)
			(min_thickness 0.25)
			(keepout
				(tracks allowed)
				(vias not_allowed)
				(pads allowed)
				(copperpour not_allowed)
				(footprints allowed)
			)
			(placement
				(enabled no)
				(sheetname "")
			)
			(fill
				(thermal_gap 0.5)
				(thermal_bridge_width 0.5)
				(island_removal_mode 0)
			)
			(polygon
				(pts
					(xy 30.6832 -90.9828) (xy 31.2928 -90.9828) (xy 31.2928 -91.1352) (xy 30.6832 -91.1352)
				)
			)
		)
		(zone
			(layer "B.Cu")
			(hatch none 0.5)
			(connect_pads
				(clearance 0)
			)
			(min_thickness 0.25)
			(keepout
				(tracks not_allowed)
				(vias allowed)
				(pads allowed)
				(copperpour not_allowed)
				(footprints allowed)
			)
			(placement
				(enabled no)
				(sheetname "")
			)
			(fill
				(thermal_gap 0.5)
				(thermal_bridge_width 0.5)
				(island_removal_mode 0)
			)
			(polygon
				(pts
					(xy 30.6832 -90.9828) (xy 31.2928 -90.9828) (xy 31.2928 -91.1352) (xy 30.6832 -91.1352)
				)
			)
		)
	)
)
